# T6G (Grand Teton) — schematic netlist excerpt (pin names and nets, part order shuffled) for the footprints in the layout excerpt that follows; sources: Cadence DE-HDL packaged netlist, KiCad conversion of 04192023_DAF0TMB3IC0_F0TG_MB_C_brd_V02_OCP.brd

PC610_3  Q_CAP  22UF 16V 20% X6S  pkg C0805  page 199 : A = SW_P12V_AUX_PVDDCR_SOC_P0_FLT ; B = GND
C360  Q_CAP  0.1UF 16V 10% X7R  pkg C0402  page 83 : A = P3V3_AUX ; B = GND
C6039  Q_CAP  0.01UF 50V 10% X7R  pkg C0402  page 177 : A = P1V2_CPU0_USB_DVDD12 ; B = GND

(kicad_pcb
	(version 20260206)
	(generator "pcbnew")
	(generator_version "10.0")
	(general
		(thickness 1.6)
		(legacy_teardrops no)
	)
	(paper "A4")
	(title_block
		(title "04192023_DAF0TMB3IC0_F0TG_MB_C_brd_V02_OCP.brd")
		(comment 1 "Grand Teton / footprints 6676-6678 of 8354")
	)
	(layers
		(0 "F.Cu" signal "TOP")
		(4 "In1.Cu" signal "GND")
		(6 "In2.Cu" signal "IN1")
		(8 "In3.Cu" signal "GND1")
		(10 "In4.Cu" signal "IN2")
		(12 "In5.Cu" signal "GND2")
		(14 "In6.Cu" signal "IN3")
		(16 "In7.Cu" signal "GND3")
		(18 "In8.Cu" signal "VCC")
		(20 "In9.Cu" signal "VCC1")
		(22 "In10.Cu" signal "GND4")
		(24 "In11.Cu" signal "IN4")
		(26 "In12.Cu" signal "GND5")
		(28 "In13.Cu" signal "IN5")
		(30 "In14.Cu" signal "GND6")
		(32 "In15.Cu" signal "IN6")
		(34 "In16.Cu" signal "GND7")
		(2 "B.Cu" signal "BOTTOM")
		(9 "F.Adhes" user "F.Adhesive")
		(11 "B.Adhes" user "B.Adhesive")
		(13 "F.Paste" user "Package Geometry/Pastemask Top")
		(15 "B.Paste" user "Package Geometry/Pastemask Bottom")
		(5 "F.SilkS" user "Ref Des/Silkscreen Top")
		(7 "B.SilkS" user "Ref Des/Silkscreen Bottom")
		(1 "F.Mask" user "Board Geometry/Soldermask Top")
		(3 "B.Mask" user "Board Geometry/Soldermask Bottom")
		(17 "Dwgs.User" user "User.Drawings")
		(19 "Cmts.User" user "User.Comments")
		(21 "Eco1.User" user "User.Eco1")
		(23 "Eco2.User" user "User.Eco2")
		(25 "Edge.Cuts" user "Board Geometry/Outline")
		(27 "Margin" user)
		(31 "F.CrtYd" user "Package Geometry/Place Bound Top")
		(29 "B.CrtYd" user "Package Geometry/Place Bound Bottom")
		(35 "F.Fab" user "Ref Des/Assembly Top")
		(33 "B.Fab" user "Ref Des/Assembly Bottom")
	)
	(footprint ""
		(layer "B.Cu")
		(at 136.040114 -34.850578)
		(property "Reference" "C6039"
			(at 0 0 0)
			(layer "B.SilkS")
			(hide yes)
			(effects
				(font
					(size 1.27 1.27)
				)
				(justify mirror)
			)
		)
		(property "Value" ""
			(at 0 0 0)
			(layer "B.Fab")
			(effects
				(font
					(size 1.27 1.27)
				)
				(justify mirror)
			)
		)
		(duplicate_pad_numbers_are_jumpers no)
		(fp_line
			(start -0.7874 -0.4064)
			(end -0.7874 0.4064)
			(stroke
				(width 0.1524)
				(type default)
			)
			(layer "B.SilkS")
		)
		(fp_line
			(start -0.7874 0.4064)
			(end 0.7874 0.4064)
			(stroke
				(width 0.1524)
				(type default)
			)
			(layer "B.SilkS")
		)
		(fp_line
			(start 0.7874 -0.4064)
			(end -0.7874 -0.4064)
			(stroke
				(width 0.1524)
				(type default)
			)
			(layer "B.SilkS")
		)
		(fp_line
			(start 0.7874 0.4064)
			(end 0.7874 -0.4064)
			(stroke
				(width 0.1524)
				(type default)
			)
			(layer "B.SilkS")
		)
		(fp_line
			(start -0.67945 -0.3048)
			(end -0.67945 0.3048)
			(stroke
				(width 0.1)
				(type default)
			)
			(layer "B.Fab")
		)
		(fp_line
			(start -0.67945 0.3048)
			(end -0.120396 0.3048)
			(stroke
				(width 0.1)
				(type default)
			)
			(layer "B.Fab")
		)
		(fp_line
			(start -0.12065 -0.3048)
			(end -0.67945 -0.3048)
			(stroke
				(width 0.1)
				(type default)
			)
			(layer "B.Fab")
		)
		(fp_line
			(start -0.12065 -0.2794)
			(end -0.12065 -0.3048)
			(stroke
				(width 0.1)
				(type default)
			)
			(layer "B.Fab")
		)
		(fp_line
			(start -0.120396 0.2794)
			(end 0.12065 0.2794)
			(stroke
				(width 0.1)
				(type default)
			)
			(layer "B.Fab")
		)
		(fp_line
			(start -0.120396 0.3048)
			(end -0.120396 0.2794)
			(stroke
				(width 0.1)
				(type default)
			)
			(layer "B.Fab")
		)
		(fp_line
			(start 0.12065 -0.305054)
			(end 0.12065 -0.2794)
			(stroke
				(width 0.1)
				(type default)
			)
			(layer "B.Fab")
		)
		(fp_line
			(start 0.12065 -0.2794)
			(end -0.12065 -0.2794)
			(stroke
				(width 0.1)
				(type default)
			)
			(layer "B.Fab")
		)
		(fp_line
			(start 0.12065 0.2794)
			(end 0.12065 0.3048)
			(stroke
				(width 0.1)
				(type default)
			)
			(layer "B.Fab")
		)
		(fp_line
			(start 0.12065 0.3048)
			(end 0.67945 0.3048)
			(stroke
				(width 0.1)
				(type default)
			)
			(layer "B.Fab")
		)
		(fp_line
			(start 0.67945 -0.305054)
			(end 0.12065 -0.305054)
			(stroke
				(width 0.1)
				(type default)
			)
			(layer "B.Fab")
		)
		(fp_line
			(start 0.67945 0.3048)
			(end 0.67945 -0.305054)
			(stroke
				(width 0.1)
				(type default)
			)
			(layer "B.Fab")
		)
		(pad "1" smd circle
			(at 0.40005 0 180)
			(size 0 0)
			(layers "B.Cu" "B.Mask" "B.Paste")
			(net "P1V2_CPU0_USB_DVDD12")
		)
		(pad "2" smd circle
			(at -0.40005 0 180)
			(size 0 0)
			(layers "B.Cu" "B.Mask" "B.Paste")
			(net "GND")
		)
	)
	(footprint ""
		(layer "B.Cu")
		(at 411.470856 -163.891468 -90)
		(property "Reference" "PC610_3"
			(at 0 0 90)
			(layer "B.SilkS")
			(hide yes)
			(effects
				(font
					(size 1.27 1.27)
				)
				(justify mirror)
			)
		)
		(property "Value" ""
			(at 0 0 90)
			(layer "B.Fab")
			(effects
				(font
					(size 1.27 1.27)
				)
				(justify mirror)
			)
		)
		(duplicate_pad_numbers_are_jumpers no)
		(fp_line
			(start -1.524 0.762)
			(end 1.524 0.762)
			(stroke
				(width 0.1524)
				(type default)
			)
			(layer "B.SilkS")
		)
		(fp_line
			(start 1.524 0.762)
			(end 1.524 -0.762)
			(stroke
				(width 0.1524)
				(type default)
			)
			(layer "B.SilkS")
		)
		(fp_line
			(start -1.524 -0.762)
			(end -1.524 0.762)
			(stroke
				(width 0.1524)
				(type default)
			)
			(layer "B.SilkS")
		)
		(fp_line
			(start 1.524 -0.762)
			(end -1.524 -0.762)
			(stroke
				(width 0.1524)
				(type default)
			)
			(layer "B.SilkS")
		)
		(fp_line
			(start -1.1049 0.724916)
			(end -1.1049 -0.724916)
			(stroke
				(width 0.1)
				(type default)
			)
			(layer "B.Fab")
		)
		(fp_line
			(start 1.1049 0.724916)
			(end -1.1049 0.724916)
			(stroke
				(width 0.1)
				(type default)
			)
			(layer "B.Fab")
		)
		(fp_line
			(start -1.1049 -0.724916)
			(end 1.1049 -0.724916)
			(stroke
				(width 0.1)
				(type default)
			)
			(layer "B.Fab")
		)
		(fp_line
			(start 1.1049 -0.724916)
			(end 1.1049 0.724916)
			(stroke
				(width 0.1)
				(type default)
			)
			(layer "B.Fab")
		)
		(pad "1" smd rect
			(at 0.889 0 270)
			(size 1.016 1.27)
			(layers "B.Cu" "B.Mask" "B.Paste")
			(net "SW_P12V_AUX_PVDDCR_SOC_P0_FLT")
		)
		(pad "2" smd rect
			(at -0.889 0 270)
			(size 1.016 1.27)
			(layers "B.Cu" "B.Mask" "B.Paste")
			(net "GND")
		)
	)
	(footprint ""
		(layer "B.Cu")
		(at 188.712094 -116.242846)
		(property "Reference" "C360"
			(at 0 0 0)
			(layer "B.SilkS")
			(hide yes)
			(effects
				(font
					(size 1.27 1.27)
				)
				(justify mirror)
			)
		)
		(property "Value" ""
			(at 0 0 0)
			(layer "B.Fab")
			(effects
				(font
					(size 1.27 1.27)
				)
				(justify mirror)
			)
		)
		(duplicate_pad_numbers_are_jumpers no)
		(fp_line
			(start -0.69215 -0.2921)
			(end -0.69215 0.2921)
			(stroke
				(width 0.1524)
				(type default)
			)
			(layer "B.SilkS")
		)
		(fp_line
			(start -0.69215 0.2921)
			(end 0.69215 0.2921)
			(stroke
				(width 0.1524)
				(type default)
			)
			(layer "B.SilkS")
		)
		(fp_line
			(start 0.69215 -0.2921)
			(end -0.69215 -0.2921)
			(stroke
				(width 0.1524)
				(type default)
			)
			(layer "B.SilkS")
		)
		(fp_line
			(start 0.69215 0.2921)
			(end 0.69215 -0.2921)
			(stroke
				(width 0.1524)
				(type default)
			)
			(layer "B.SilkS")
		)
		(fp_line
			(start -0.51435 -0.2794)
			(end -0.51435 0.2794)
			(stroke
				(width 0.1)
				(type default)
			)
			(layer "B.Fab")
		)
		(fp_line
			(start -0.51435 0.2794)
			(end 0.51435 0.2794)
			(stroke
				(width 0.1)
				(type default)
			)
			(layer "B.Fab")
		)
		(fp_line
			(start 0.51435 -0.2794)
			(end -0.51435 -0.2794)
			(stroke
				(width 0.1)
				(type default)
			)
			(layer "B.Fab")
		)
		(fp_line
			(start 0.51435 0.2794)
			(end 0.51435 -0.2794)
			(stroke
				(width 0.1)
				(type default)
			)
			(layer "B.Fab")
		)
		(pad "1" smd circle
			(at 0.40005 0 180)
			(size 0 0)
			(layers "B.Cu" "B.Mask" "B.Paste")
			(net "P3V3_AUX")
		)
		(pad "2" smd circle
			(at -0.40005 0 180)
			(size 0 0)
			(layers "B.Cu" "B.Mask" "B.Paste")
			(net "GND")
		)
		(zone
			(layer "B.Cu")
			(hatch none 0.5)
			(connect_pads
				(clearance 0)
			)
			(min_thickness 0.25)
			(keepout
				(tracks not_allowed)
				(vias allowed)
				(pads allowed)
				(copperpour not_allowed)
				(footprints allowed)
			)
			(placement
				(enabled no)
				(sheetname "")
			)
			(fill
				(thermal_gap 0.5)
				(thermal_bridge_width 0.5)
				(island_removal_mode 0)
			)
			(polygon
				(pts
					(xy 188.521594 -116.155216) (xy 188.521594 -116.330476) (xy 188.611764 -116.388896) (xy 188.811154 -116.388896)
					(xy 188.902594 -116.33073) (xy 188.902594 -116.155216) (xy 188.811154 -116.09705) (xy 188.611764 -116.09705)
				)
			)
		)
	)
)
